# T6G (Grand Teton) — schematic netlist excerpt (pin names and nets, part order shuffled) for the footprints in the layout excerpt that follows; sources: Cadence DE-HDL packaged netlist, KiCad conversion of 04192023_DAF0TMB3IC0_F0TG_MB_C_brd_V02_OCP.brd

R5008  Q_RES  1K 1% EMPTY  pkg 0402LF  page 159 : A = PVDD11_S3_P0 ; B = I3C_SPD_DDRGL_CPU0_LVC1_SCL
R5377  Q_RES  0 5% CHIP  pkg 0402LF  page 144 : A = HDD_ACTIVITY_BUF_N ; B = PU_BUFFER_HDD_ACTIVITY

(kicad_pcb
	(version 20260206)
	(generator "pcbnew")
	(generator_version "10.0")
	(general
		(thickness 1.6)
		(legacy_teardrops no)
	)
	(paper "A4")
	(title_block
		(title "04192023_DAF0TMB3IC0_F0TG_MB_C_brd_V02_OCP.brd")
		(comment 1 "Grand Teton / footprints 4018-4019 of 8354")
	)
	(layers
		(0 "F.Cu" signal "TOP")
		(4 "In1.Cu" signal "GND")
		(6 "In2.Cu" signal "IN1")
		(8 "In3.Cu" signal "GND1")
		(10 "In4.Cu" signal "IN2")
		(12 "In5.Cu" signal "GND2")
		(14 "In6.Cu" signal "IN3")
		(16 "In7.Cu" signal "GND3")
		(18 "In8.Cu" signal "VCC")
		(20 "In9.Cu" signal "VCC1")
		(22 "In10.Cu" signal "GND4")
		(24 "In11.Cu" signal "IN4")
		(26 "In12.Cu" signal "GND5")
		(28 "In13.Cu" signal "IN5")
		(30 "In14.Cu" signal "GND6")
		(32 "In15.Cu" signal "IN6")
		(34 "In16.Cu" signal "GND7")
		(2 "B.Cu" signal "BOTTOM")
		(9 "F.Adhes" user "F.Adhesive")
		(11 "B.Adhes" user "B.Adhesive")
		(13 "F.Paste" user "Package Geometry/Pastemask Top")
		(15 "B.Paste" user "Package Geometry/Pastemask Bottom")
		(5 "F.SilkS" user "Ref Des/Silkscreen Top")
		(7 "B.SilkS" user "Ref Des/Silkscreen Bottom")
		(1 "F.Mask" user "Board Geometry/Soldermask Top")
		(3 "B.Mask" user "Board Geometry/Soldermask Bottom")
		(17 "Dwgs.User" user "User.Drawings")
		(19 "Cmts.User" user "User.Comments")
		(21 "Eco1.User" user "User.Eco1")
		(23 "Eco2.User" user "User.Eco2")
		(25 "Edge.Cuts" user "Board Geometry/Outline")
		(27 "Margin" user)
		(31 "F.CrtYd" user "Package Geometry/Place Bound Top")
		(29 "B.CrtYd" user "Package Geometry/Place Bound Bottom")
		(35 "F.Fab" user "Ref Des/Assembly Top")
		(33 "B.Fab" user "Ref Des/Assembly Bottom")
	)
	(footprint ""
		(layer "F.Cu")
		(at 434.678836 -168.208452)
		(property "Reference" "R5008"
			(at 0 0 0)
			(layer "F.SilkS")
			(hide yes)
			(effects
				(font
					(size 1.27 1.27)
				)
			)
		)
		(property "Value" ""
			(at 0 0 0)
			(layer "F.Fab")
			(effects
				(font
					(size 1.27 1.27)
				)
			)
		)
		(duplicate_pad_numbers_are_jumpers no)
		(fp_line
			(start -0.7874 -0.4064)
			(end 0.7874 -0.4064)
			(stroke
				(width 0.1524)
				(type default)
			)
			(layer "F.SilkS")
		)
		(fp_line
			(start -0.7874 0.4064)
			(end -0.7874 -0.4064)
			(stroke
				(width 0.1524)
				(type default)
			)
			(layer "F.SilkS")
		)
		(fp_line
			(start 0.7874 -0.4064)
			(end 0.7874 0.4064)
			(stroke
				(width 0.1524)
				(type default)
			)
			(layer "F.SilkS")
		)
		(fp_line
			(start 0.7874 0.4064)
			(end -0.7874 0.4064)
			(stroke
				(width 0.1524)
				(type default)
			)
			(layer "F.SilkS")
		)
		(fp_line
			(start -0.67945 -0.305054)
			(end -0.12065 -0.305054)
			(stroke
				(width 0.1)
				(type default)
			)
			(layer "F.Fab")
		)
		(fp_line
			(start -0.67945 0.3048)
			(end -0.67945 -0.305054)
			(stroke
				(width 0.1)
				(type default)
			)
			(layer "F.Fab")
		)
		(fp_line
			(start -0.12065 -0.305054)
			(end -0.12065 -0.2794)
			(stroke
				(width 0.1)
				(type default)
			)
			(layer "F.Fab")
		)
		(fp_line
			(start -0.12065 -0.2794)
			(end 0.12065 -0.2794)
			(stroke
				(width 0.1)
				(type default)
			)
			(layer "F.Fab")
		)
		(fp_line
			(start -0.12065 0.2794)
			(end -0.12065 0.3048)
			(stroke
				(width 0.1)
				(type default)
			)
			(layer "F.Fab")
		)
		(fp_line
			(start -0.12065 0.3048)
			(end -0.67945 0.3048)
			(stroke
				(width 0.1)
				(type default)
			)
			(layer "F.Fab")
		)
		(fp_line
			(start 0.120396 0.2794)
			(end -0.12065 0.2794)
			(stroke
				(width 0.1)
				(type default)
			)
			(layer "F.Fab")
		)
		(fp_line
			(start 0.120396 0.3048)
			(end 0.120396 0.2794)
			(stroke
				(width 0.1)
				(type default)
			)
			(layer "F.Fab")
		)
		(fp_line
			(start 0.12065 -0.3048)
			(end 0.67945 -0.3048)
			(stroke
				(width 0.1)
				(type default)
			)
			(layer "F.Fab")
		)
		(fp_line
			(start 0.12065 -0.2794)
			(end 0.12065 -0.3048)
			(stroke
				(width 0.1)
				(type default)
			)
			(layer "F.Fab")
		)
		(fp_line
			(start 0.67945 -0.3048)
			(end 0.67945 0.3048)
			(stroke
				(width 0.1)
				(type default)
			)
			(layer "F.Fab")
		)
		(fp_line
			(start 0.67945 0.3048)
			(end 0.120396 0.3048)
			(stroke
				(width 0.1)
				(type default)
			)
			(layer "F.Fab")
		)
		(pad "1" smd circle
			(at -0.40005 0)
			(size 0 0)
			(layers "F.Cu" "F.Mask" "F.Paste")
			(net "PVDD11_S3_P0")
		)
		(pad "2" smd circle
			(at 0.40005 0)
			(size 0 0)
			(layers "F.Cu" "F.Mask" "F.Paste")
			(net "I3C_SPD_DDRGL_CPU0_LVC1_SCL")
		)
	)
	(footprint ""
		(layer "F.Cu")
		(at 148.494242 -104.608884)
		(property "Reference" "R5377"
			(at 0 0 0)
			(layer "F.SilkS")
			(hide yes)
			(effects
				(font
					(size 1.27 1.27)
				)
			)
		)
		(property "Value" ""
			(at 0 0 0)
			(layer "F.Fab")
			(effects
				(font
					(size 1.27 1.27)
				)
			)
		)
		(duplicate_pad_numbers_are_jumpers no)
		(fp_line
			(start -0.7874 -0.4064)
			(end 0.7874 -0.4064)
			(stroke
				(width 0.1524)
				(type default)
			)
			(layer "F.SilkS")
		)
		(fp_line
			(start -0.7874 0.4064)
			(end -0.7874 -0.4064)
			(stroke
				(width 0.1524)
				(type default)
			)
			(layer "F.SilkS")
		)
		(fp_line
			(start 0.7874 -0.4064)
			(end 0.7874 0.4064)
			(stroke
				(width 0.1524)
				(type default)
			)
			(layer "F.SilkS")
		)
		(fp_line
			(start 0.7874 0.4064)
			(end -0.7874 0.4064)
			(stroke
				(width 0.1524)
				(type default)
			)
			(layer "F.SilkS")
		)
		(fp_line
			(start -0.67945 -0.305054)
			(end -0.12065 -0.305054)
			(stroke
				(width 0.1)
				(type default)
			)
			(layer "F.Fab")
		)
		(fp_line
			(start -0.67945 0.3048)
			(end -0.67945 -0.305054)
			(stroke
				(width 0.1)
				(type default)
			)
			(layer "F.Fab")
		)
		(fp_line
			(start -0.12065 -0.305054)
			(end -0.12065 -0.2794)
			(stroke
				(width 0.1)
				(type default)
			)
			(layer "F.Fab")
		)
		(fp_line
			(start -0.12065 -0.2794)
			(end 0.12065 -0.2794)
			(stroke
				(width 0.1)
				(type default)
			)
			(layer "F.Fab")
		)
		(fp_line
			(start -0.12065 0.2794)
			(end -0.12065 0.3048)
			(stroke
				(width 0.1)
				(type default)
			)
			(layer "F.Fab")
		)
		(fp_line
			(start -0.12065 0.3048)
			(end -0.67945 0.3048)
			(stroke
				(width 0.1)
				(type default)
			)
			(layer "F.Fab")
		)
		(fp_line
			(start 0.120396 0.2794)
			(end -0.12065 0.2794)
			(stroke
				(width 0.1)
				(type default)
			)
			(layer "F.Fab")
		)
		(fp_line
			(start 0.120396 0.3048)
			(end 0.120396 0.2794)
			(stroke
				(width 0.1)
				(type default)
			)
			(layer "F.Fab")
		)
		(fp_line
			(start 0.12065 -0.3048)
			(end 0.67945 -0.3048)
			(stroke
				(width 0.1)
				(type default)
			)
			(layer "F.Fab")
		)
		(fp_line
			(start 0.12065 -0.2794)
			(end 0.12065 -0.3048)
			(stroke
				(width 0.1)
				(type default)
			)
			(layer "F.Fab")
		)
		(fp_line
			(start 0.67945 -0.3048)
			(end 0.67945 0.3048)
			(stroke
				(width 0.1)
				(type default)
			)
			(layer "F.Fab")
		)
		(fp_line
			(start 0.67945 0.3048)
			(end 0.120396 0.3048)
			(stroke
				(width 0.1)
				(type default)
			)
			(layer "F.Fab")
		)
		(pad "1" smd circle
			(at -0.40005 0)
			(size 0 0)
			(layers "F.Cu" "F.Mask" "F.Paste")
			(net "HDD_ACTIVITY_BUF_N")
		)
		(pad "2" smd circle
			(at 0.40005 0)
			(size 0 0)
			(layers "F.Cu" "F.Mask" "F.Paste")
			(net "PU_BUFFER_HDD_ACTIVITY")
		)
	)
)
